# BASEBOARD_FAB2 (Tioga Pass) — schematic netlist excerpt (pin names and nets, part order shuffled) for the footprints in the layout excerpt that follows; sources: Cadence DE-HDL packaged netlist, KiCad conversion of Wiwynn_Tioga_Pass_MB.brd

J9T1  SCONN288_H44441003  SCONN  pkg PIP  page 78
  \12v\(1)  = P12V_NVDIMM_GHJ
  VSS(93)  = GND
  DQ(4)  = M_G_DQ<4>
  VSS(92)  = GND
  DQ(0)  = M_G_DQ<0>
  VSS(91)  = GND
  DQS9P  = M_G_DQS_DP<9>
  DQS9N  = M_G_DQS_DN<9>
  VSS(90)  = GND
  DQ(6)  = M_G_DQ<6>
  VSS(89)  = GND
  DQ(2)  = M_G_DQ<2>
  VSS(88)  = GND
  DQ(12)  = M_G_DQ<12>
  VSS(87)  = GND
  DQ(8)  = M_G_DQ<8>
  VSS(86)  = GND
  DQS10P  = M_G_DQS_DP<10>
  DQS10N  = M_G_DQS_DN<10>
  VSS(85)  = GND
  DQ(14)  = M_G_DQ<14>
  VSS(84)  = GND
  DQ(10)  = M_G_DQ<10>
  VSS(83)  = GND
  DQ(20)  = M_G_DQ<20>
  VSS(82)  = GND
  DQ(16)  = M_G_DQ<16>
  VSS(81)  = GND
  DQS11P  = M_G_DQS_DP<11>
  DQS11N  = M_G_DQS_DN<11>
  VSS(80)  = GND
  DQ(22)  = M_G_DQ<22>
  VSS(79)  = GND
  DQ(18)  = M_G_DQ<18>
  VSS(78)  = GND
  DQ(28)  = M_G_DQ<28>
  VSS(77)  = GND
  DQ(24)  = M_G_DQ<24>
  VSS(76)  = GND
  DQS12P  = M_G_DQS_DP<12>
  DQS12N  = M_G_DQS_DN<12>
  VSS(75)  = GND
  DQ(30)  = M_G_DQ<30>
  VSS(74)  = GND
  DQ(26)  = M_G_DQ<26>
  VSS(73)  = GND
  CB(4)  = M_G_ECC<4>
  VSS(72)  = GND
  CB(0)  = M_G_ECC<0>
  VSS(71)  = GND
  DQS17P  = M_G_DQS_DP<17>
  DQS17N  = M_G_DQS_DN<17>
  VSS(70)  = GND
  CB(6)  = M_G_ECC<6>
  VSS(69)  = GND
  CB(2)  = M_G_ECC<2>
  VSS(68)  = GND
  RESET_N  = M_GHJ_RST_N
  VDD(25)  = PVDDQ_GHJ
  CKE(0)  = M_G_CKE<2>
  VDD(24)  = PVDDQ_GHJ
  ACT_N  = M_G_ACT_N
  BG(0)  = M_G_BG<0>
  VDD(23)  = PVDDQ_GHJ
  A12  = M_G_MA<12>
  A9  = M_G_MA<9>
  VDD(22)  = PVDDQ_GHJ
  A8  = M_G_MA<8>
  A6  = M_G_MA<6>
  VDD(21)  = PVDDQ_GHJ
  A3  = M_G_MA<3>
  A1  = M_G_MA<1>
  VDD(20)  = PVDDQ_GHJ
  CK0P  = M_G_CLK_DP<2>
  CK0N  = M_G_CLK_DN<2>
  VDD(19)  = PVDDQ_GHJ
  VTT(1)  = PVTT_GHJ
  EVENT_N  = FM_DIMM_EVENT_COD_N
  A0  = M_G_MA<0>
  VDD(18)  = PVDDQ_GHJ
  BA(0)  = M_G_BA<0>
  A16_RAS_N  = M_G_MA<16>
  VDD(17)  = PVDDQ_GHJ
  S0_N  = M_G_CS_N<4>
  VDD(16)  = PVDDQ_GHJ
  A15_CAS_N  = M_G_MA<15>
  ODT(0)  = M_G_ODT<2>
  VDD(15)  = PVDDQ_GHJ
  S1_N  = M_G_CS_N<5>
  VDD(14)  = PVDDQ_GHJ
  ODT(1)  = M_G_ODT<3>
  VDD(13)  = PVDDQ_GHJ
  S2_N_C(0)  = M_G_CS_N<6>
  VSS(67)  = GND
  DQ(36)  = M_G_DQ<36>
  VSS(66)  = GND
  DQ(32)  = M_G_DQ<32>
  VSS(65)  = GND
  DQS13P  = M_G_DQS_DP<13>
  DQS13N  = M_G_DQS_DN<13>
  VSS(64)  = GND
  DQ(38)  = M_G_DQ<38>
  VSS(63)  = GND
  DQ(34)  = M_G_DQ<34>
  VSS(62)  = GND
  DQ(44)  = M_G_DQ<44>
  VSS(61)  = GND
  DQ(40)  = M_G_DQ<40>
  VSS(60)  = GND
  DQS14P  = M_G_DQS_DP<14>
  DQS14N  = M_G_DQS_DN<14>
  VSS(59)  = GND
  DQ(46)  = M_G_DQ<46>
  VSS(58)  = GND
  DQ(42)  = M_G_DQ<42>
  VSS(57)  = GND
  DQ(52)  = M_G_DQ<52>
  VSS(56)  = GND
  DQ(48)  = M_G_DQ<48>
  VSS(55)  = GND
  DQS15P  = M_G_DQS_DP<15>
  DQS15N  = M_G_DQS_DN<15>
  VSS(54)  = GND
  DQ(54)  = M_G_DQ<54>
  VSS(53)  = GND
  DQ(50)  = M_G_DQ<50>
  VSS(52)  = GND
  DQ(60)  = M_G_DQ<60>
  VSS(51)  = GND
  DQ(56)  = M_G_DQ<56>
  VSS(50)  = GND
  DQS16P  = M_G_DQS_DP<16>
  DQS16N  = M_G_DQS_DN<16>
  VSS(49)  = GND
  DQ(62)  = M_G_DQ<62>
  VSS(48)  = GND
  DQ(58)  = M_G_DQ<58>
  VSS(47)  = GND
  SA(0)  = PVPP_GHJ
  SA(1)  = GND
  SCL  = SMB_DDR_GHJ_VPP_SCL
  VPP(4)  = PVPP_GHJ
  VPP(3)  = PVPP_GHJ
  RFU(2)  = TP_CH_G_DIMM0_RFU_2
  \12v\(0)  = P12V_NVDIMM_GHJ
  VREFCA  = M_G_VREF
  VSS(46)  = GND
  DQ(5)  = M_G_DQ<5>
  VSS(45)  = GND
  DQ(1)  = M_G_DQ<1>
  VSS(44)  = GND
  DQS0N  = M_G_DQS_DN<0>
  DQS0P  = M_G_DQS_DP<0>
  VSS(43)  = GND
  DQ(7)  = M_G_DQ<7>
  VSS(42)  = GND
  DQ(3)  = M_G_DQ<3>
  VSS(41)  = GND
  DQ(13)  = M_G_DQ<13>
  VSS(40)  = GND
  DQ(9)  = M_G_DQ<9>
  VSS(39)  = GND
  DQS1N  = M_G_DQS_DN<1>
  DQS1P  = M_G_DQS_DP<1>
  VSS(38)  = GND
  DQ(15)  = M_G_DQ<15>
  VSS(37)  = GND
  DQ(11)  = M_G_DQ<11>
  VSS(36)  = GND
  DQ(21)  = M_G_DQ<21>
  VSS(35)  = GND
  DQ(17)  = M_G_DQ<17>
  VSS(34)  = GND
  DQS2N  = M_G_DQS_DN<2>
  DQS2P  = M_G_DQS_DP<2>
  VSS(33)  = GND
  DQ(23)  = M_G_DQ<23>
  VSS(32)  = GND
  DQ(19)  = M_G_DQ<19>
  VSS(31)  = GND
  DQ(29)  = M_G_DQ<29>
  VSS(30)  = GND
  DQ(25)  = M_G_DQ<25>
  VSS(29)  = GND
  DQS3N  = M_G_DQS_DN<3>
  DQS3P  = M_G_DQS_DP<3>
  VSS(28)  = GND
  DQ(31)  = M_G_DQ<31>
  VSS(27)  = GND
  DQ(27)  = M_G_DQ<27>
  VSS(26)  = GND
  CB(5)  = M_G_ECC<5>
  VSS(25)  = GND
  CB(1)  = M_G_ECC<1>
  VSS(24)  = GND
  DQS8N  = M_G_DQS_DN<8>
  DQS8P  = M_G_DQS_DP<8>
  VSS(23)  = GND
  CB(7)  = M_G_ECC<7>
  VSS(22)  = GND
  CB(3)  = M_G_ECC<3>
  VSS(21)  = GND
  CKE(1)  = M_G_CKE<3>
  VDD(12)  = PVDDQ_GHJ
  RFU(0)  = TP_CH_G_DIMM0_RFU_0
  VDD(11)  = PVDDQ_GHJ
  BG(1)  = M_G_BG<1>
  ALERT_N  = M_G_ALERT_N
  VDD(10)  = PVDDQ_GHJ
  A11  = M_G_MA<11>
  A7  = M_G_MA<7>
  VDD(9)  = PVDDQ_GHJ
  A5  = M_G_MA<5>
  A4  = M_G_MA<4>
  VDD(8)  = PVDDQ_GHJ
  A2  = M_G_MA<2>
  VDD(7)  = PVDDQ_GHJ
  CK1P  = M_G_CLK_DP<3>
  CK1N  = M_G_CLK_DN<3>
  VDD(6)  = PVDDQ_GHJ
  VTT(0)  = PVTT_GHJ
  PAR  = M_G_PAR
  VDD(5)  = PVDDQ_GHJ
  BA(1)  = M_G_BA<1>
  A10  = M_G_MA<10>
  VDD(4)  = PVDDQ_GHJ
  RFU(1)  = TP_CH_G_DIMM0_RFU_1
  A14_WE_N  = M_G_MA<14>
  VDD(3)  = PVDDQ_GHJ
  SAVE_N_NC  = FM_ADR_COMPLETE_GHJ_N
  VDD(2)  = PVDDQ_GHJ
  A13  = M_G_MA<13>
  VDD(1)  = PVDDQ_GHJ
  A17  = M_G_MA<17>
  C(2)  = M_G_C<2>
  VDD(0)  = PVDDQ_GHJ
  S3_N_C(1)  = M_G_CS_N<7>
  SA(2)  = GND
  VSS(20)  = GND
  DQ(37)  = M_G_DQ<37>
  VSS(19)  = GND
  DQ(33)  = M_G_DQ<33>
  VSS(18)  = GND
  DQS4N  = M_G_DQS_DN<4>
  DQS4P  = M_G_DQS_DP<4>
  VSS(17)  = GND
  DQ(39)  = M_G_DQ<39>
  VSS(16)  = GND
  DQ(35)  = M_G_DQ<35>
  VSS(15)  = GND
  DQ(45)  = M_G_DQ<45>
  VSS(14)  = GND
  DQ(41)  = M_G_DQ<41>
  VSS(13)  = GND
  DQS5N  = M_G_DQS_DN<5>
  DQS5P  = M_G_DQS_DP<5>
  VSS(12)  = GND
  DQ(47)  = M_G_DQ<47>
  VSS(11)  = GND
  DQ(43)  = M_G_DQ<43>
  VSS(10)  = GND
  DQ(53)  = M_G_DQ<53>
  VSS(9)  = GND
  DQ(49)  = M_G_DQ<49>
  VSS(8)  = GND
  DQS6N  = M_G_DQS_DN<6>
  DQS6P  = M_G_DQS_DP<6>
  VSS(7)  = GND
  DQ(55)  = M_G_DQ<55>
  VSS(6)  = GND
  DQ(51)  = M_G_DQ<51>
  VSS(5)  = GND
  DQ(61)  = M_G_DQ<61>
  VSS(4)  = GND
  DQ(57)  = M_G_DQ<57>
  VSS(3)  = GND
  DQS7N  = M_G_DQS_DN<7>
  DQS7P  = M_G_DQS_DP<7>
  VSS(2)  = GND
  DQ(63)  = M_G_DQ<63>
  VSS(1)  = GND
  DQ(59)  = M_G_DQ<59>
  VSS(0)  = GND
  VDDSPD  = PVPP_GHJ
  SDA  = SMB_DDR_GHJ_VPP_SDA
  VPP(1)  = PVPP_GHJ
  VPP(0)  = PVPP_GHJ
  VPP(2)  = PVPP_GHJ

(kicad_pcb
	(version 20260206)
	(generator "pcbnew")
	(generator_version "10.0")
	(general
		(thickness 1.6)
		(legacy_teardrops no)
	)
	(paper "A4")
	(title_block
		(title "Wiwynn_Tioga_Pass_MB.brd")
		(comment 1 "Tioga Pass / footprint 4084 of 4770 (J9T1), pads 101-151 of 291")
	)
	(layers
		(0 "F.Cu" signal "TOP")
		(4 "In1.Cu" signal "L2GND")
		(6 "In2.Cu" signal "L3")
		(8 "In3.Cu" signal "L4GND")
		(10 "In4.Cu" signal "L5")
		(12 "In5.Cu" signal "L6GND")
		(14 "In6.Cu" signal "L7VCC")
		(16 "In7.Cu" signal "L8VCC")
		(18 "In8.Cu" signal "L9GND")
		(20 "In9.Cu" signal "L10")
		(22 "In10.Cu" signal "L11GND")
		(24 "In11.Cu" signal "L12")
		(26 "In12.Cu" signal "L13GND")
		(2 "B.Cu" signal "BOTTOM")
		(9 "F.Adhes" user "F.Adhesive")
		(11 "B.Adhes" user "B.Adhesive")
		(13 "F.Paste" user "Package Geometry/Pastemask Top")
		(15 "B.Paste" user "Package Geometry/Pastemask Bottom")
		(5 "F.SilkS" user "Ref Des/Silkscreen Top")
		(7 "B.SilkS" user "Ref Des/Silkscreen Bottom")
		(1 "F.Mask" user "Board Geometry/Soldermask Top")
		(3 "B.Mask" user "Board Geometry/Soldermask Bottom")
		(17 "Dwgs.User" user "User.Drawings")
		(19 "Cmts.User" user "User.Comments")
		(21 "Eco1.User" user "User.Eco1")
		(23 "Eco2.User" user "User.Eco2")
		(25 "Edge.Cuts" user "Board Geometry/Outline")
		(27 "Margin" user)
		(31 "F.CrtYd" user "Package Geometry/Place Bound Top")
		(29 "B.CrtYd" user "Package Geometry/Place Bound Bottom")
		(35 "F.Fab" user "Ref Des/Assembly Top")
		(33 "B.Fab" user "Ref Des/Assembly Bottom")
	)
	(footprint ""
		(layer "B.Cu")
		(at 29.699458 -24.824182 90)
		(property "Reference" "J9T1"
			(at 2.200148 39.261542 0)
			(unlocked yes)
			(layer "B.SilkS")
			(effects
				(font
					(size 0.7874 0.5842)
					(thickness 0.1524)
				)
				(justify left mirror)
			)
		)
		(property "Value" ""
			(at 0 0 90)
			(layer "B.Fab")
			(effects
				(font
					(size 1.27 1.27)
				)
				(justify mirror)
			)
		)
		(duplicate_pad_numbers_are_jumpers no)
		(pad "98" smd rect
			(at 0 87.54999 270)
			(size 1.8034 0.508)
			(layers "B.Cu" "B.Mask" "B.Paste")
			(net "GND")
		)
		(pad "99" smd rect
			(at 0 88.399874 270)
			(size 1.8034 0.508)
			(layers "B.Cu" "B.Mask" "B.Paste")
			(net "M_G_DQS_DP<13>")
		)
		(pad "100" smd rect
			(at 0 89.250012 270)
			(size 1.8034 0.508)
			(layers "B.Cu" "B.Mask" "B.Paste")
			(net "M_G_DQS_DN<13>")
		)
		(pad "101" smd rect
			(at 0 90.099896 270)
			(size 1.8034 0.508)
			(layers "B.Cu" "B.Mask" "B.Paste")
			(net "GND")
		)
		(pad "102" smd rect
			(at 0 90.950034 270)
			(size 1.8034 0.508)
			(layers "B.Cu" "B.Mask" "B.Paste")
			(net "M_G_DQ<38>")
		)
		(pad "103" smd rect
			(at 0 91.799918 270)
			(size 1.8034 0.508)
			(layers "B.Cu" "B.Mask" "B.Paste")
			(net "GND")
		)
		(pad "104" smd rect
			(at 0 92.650056 270)
			(size 1.8034 0.508)
			(layers "B.Cu" "B.Mask" "B.Paste")
			(net "M_G_DQ<34>")
		)
		(pad "105" smd rect
			(at 0 93.49994 270)
			(size 1.8034 0.508)
			(layers "B.Cu" "B.Mask" "B.Paste")
			(net "GND")
		)
		(pad "106" smd rect
			(at 0 94.350078 270)
			(size 1.8034 0.508)
			(layers "B.Cu" "B.Mask" "B.Paste")
			(net "M_G_DQ<44>")
		)
		(pad "107" smd rect
			(at 0 95.199962 270)
			(size 1.8034 0.508)
			(layers "B.Cu" "B.Mask" "B.Paste")
			(net "GND")
		)
		(pad "108" smd rect
			(at 0 96.0501 270)
			(size 1.8034 0.508)
			(layers "B.Cu" "B.Mask" "B.Paste")
			(net "M_G_DQ<40>")
		)
		(pad "109" smd rect
			(at 0 96.899984 270)
			(size 1.8034 0.508)
			(layers "B.Cu" "B.Mask" "B.Paste")
			(net "GND")
		)
		(pad "110" smd rect
			(at 0 97.750122 270)
			(size 1.8034 0.508)
			(layers "B.Cu" "B.Mask" "B.Paste")
			(net "M_G_DQS_DP<14>")
		)
		(pad "111" smd rect
			(at 0 98.600006 270)
			(size 1.8034 0.508)
			(layers "B.Cu" "B.Mask" "B.Paste")
			(net "M_G_DQS_DN<14>")
		)
		(pad "112" smd rect
			(at 0 99.44989 270)
			(size 1.8034 0.508)
			(layers "B.Cu" "B.Mask" "B.Paste")
			(net "GND")
		)
		(pad "113" smd rect
			(at 0 100.300028 270)
			(size 1.8034 0.508)
			(layers "B.Cu" "B.Mask" "B.Paste")
			(net "M_G_DQ<46>")
		)
		(pad "114" smd rect
			(at 0 101.149912 270)
			(size 1.8034 0.508)
			(layers "B.Cu" "B.Mask" "B.Paste")
			(net "GND")
		)
		(pad "115" smd rect
			(at 0 102.00005 270)
			(size 1.8034 0.508)
			(layers "B.Cu" "B.Mask" "B.Paste")
			(net "M_G_DQ<42>")
		)
		(pad "116" smd rect
			(at 0 102.849934 270)
			(size 1.8034 0.508)
			(layers "B.Cu" "B.Mask" "B.Paste")
			(net "GND")
		)
		(pad "117" smd rect
			(at 0 103.700072 270)
			(size 1.8034 0.508)
			(layers "B.Cu" "B.Mask" "B.Paste")
			(net "M_G_DQ<52>")
		)
		(pad "118" smd rect
			(at 0 104.549956 270)
			(size 1.8034 0.508)
			(layers "B.Cu" "B.Mask" "B.Paste")
			(net "GND")
		)
		(pad "119" smd rect
			(at 0 105.400094 270)
			(size 1.8034 0.508)
			(layers "B.Cu" "B.Mask" "B.Paste")
			(net "M_G_DQ<48>")
		)
		(pad "120" smd rect
			(at 0 106.249978 270)
			(size 1.8034 0.508)
			(layers "B.Cu" "B.Mask" "B.Paste")
			(net "GND")
		)
		(pad "121" smd rect
			(at 0 107.100116 270)
			(size 1.8034 0.508)
			(layers "B.Cu" "B.Mask" "B.Paste")
			(net "M_G_DQS_DP<15>")
		)
		(pad "122" smd rect
			(at 0 107.95 270)
			(size 1.8034 0.508)
			(layers "B.Cu" "B.Mask" "B.Paste")
			(net "M_G_DQS_DN<15>")
		)
		(pad "123" smd rect
			(at 0 108.799884 270)
			(size 1.8034 0.508)
			(layers "B.Cu" "B.Mask" "B.Paste")
			(net "GND")
		)
		(pad "124" smd rect
			(at 0 109.650022 270)
			(size 1.8034 0.508)
			(layers "B.Cu" "B.Mask" "B.Paste")
			(net "M_G_DQ<54>")
		)
		(pad "125" smd rect
			(at 0 110.499906 270)
			(size 1.8034 0.508)
			(layers "B.Cu" "B.Mask" "B.Paste")
			(net "GND")
		)
		(pad "126" smd rect
			(at 0 111.350044 270)
			(size 1.8034 0.508)
			(layers "B.Cu" "B.Mask" "B.Paste")
			(net "M_G_DQ<50>")
		)
		(pad "127" smd rect
			(at 0 112.199928 270)
			(size 1.8034 0.508)
			(layers "B.Cu" "B.Mask" "B.Paste")
			(net "GND")
		)
		(pad "128" smd rect
			(at 0 113.050066 270)
			(size 1.8034 0.508)
			(layers "B.Cu" "B.Mask" "B.Paste")
			(net "M_G_DQ<60>")
		)
		(pad "129" smd rect
			(at 0 113.89995 270)
			(size 1.8034 0.508)
			(layers "B.Cu" "B.Mask" "B.Paste")
			(net "GND")
		)
		(pad "130" smd rect
			(at 0 114.750088 270)
			(size 1.8034 0.508)
			(layers "B.Cu" "B.Mask" "B.Paste")
			(net "M_G_DQ<56>")
		)
		(pad "131" smd rect
			(at 0 115.599972 270)
			(size 1.8034 0.508)
			(layers "B.Cu" "B.Mask" "B.Paste")
			(net "GND")
		)
		(pad "132" smd rect
			(at 0 116.45011 270)
			(size 1.8034 0.508)
			(layers "B.Cu" "B.Mask" "B.Paste")
			(net "M_G_DQS_DP<16>")
		)
		(pad "133" smd rect
			(at 0 117.299994 270)
			(size 1.8034 0.508)
			(layers "B.Cu" "B.Mask" "B.Paste")
			(net "M_G_DQS_DN<16>")
		)
		(pad "134" smd rect
			(at 0 118.149878 270)
			(size 1.8034 0.508)
			(layers "B.Cu" "B.Mask" "B.Paste")
			(net "GND")
		)
		(pad "135" smd rect
			(at 0 119.000016 270)
			(size 1.8034 0.508)
			(layers "B.Cu" "B.Mask" "B.Paste")
			(net "M_G_DQ<62>")
		)
		(pad "136" smd rect
			(at 0 119.8499 270)
			(size 1.8034 0.508)
			(layers "B.Cu" "B.Mask" "B.Paste")
			(net "GND")
		)
		(pad "137" smd rect
			(at 0 120.700038 270)
			(size 1.8034 0.508)
			(layers "B.Cu" "B.Mask" "B.Paste")
			(net "M_G_DQ<58>")
		)
		(pad "138" smd rect
			(at 0 121.549922 270)
			(size 1.8034 0.508)
			(layers "B.Cu" "B.Mask" "B.Paste")
			(net "GND")
		)
		(pad "139" smd rect
			(at 0 122.40006 270)
			(size 1.8034 0.508)
			(layers "B.Cu" "B.Mask" "B.Paste")
			(net "PVPP_GHJ")
		)
		(pad "140" smd rect
			(at 0 123.249944 270)
			(size 1.8034 0.508)
			(layers "B.Cu" "B.Mask" "B.Paste")
			(net "GND")
		)
		(pad "141" smd rect
			(at 0 124.100082 270)
			(size 1.8034 0.508)
			(layers "B.Cu" "B.Mask" "B.Paste")
			(net "SMB_DDR_GHJ_VPP_SCL")
		)
		(pad "142" smd rect
			(at 0 124.949966 270)
			(size 1.8034 0.508)
			(layers "B.Cu" "B.Mask" "B.Paste")
			(net "PVPP_GHJ")
		)
		(pad "143" smd rect
			(at 0 125.800104 270)
			(size 1.8034 0.508)
			(layers "B.Cu" "B.Mask" "B.Paste")
			(net "PVPP_GHJ")
		)
		(pad "144" smd rect
			(at 0 126.649988 270)
			(size 1.8034 0.508)
			(layers "B.Cu" "B.Mask" "B.Paste")
			(net "TP_CH_G_DIMM0_RFU_2")
		)
		(pad "145" smd rect
			(at -4.59994 0 270)
			(size 1.8034 0.508)
			(layers "B.Cu" "B.Mask" "B.Paste")
			(net "P12V_NVDIMM_GHJ")
		)
		(pad "146" smd rect
			(at -4.59994 0.849884 270)
			(size 1.8034 0.508)
			(layers "B.Cu" "B.Mask" "B.Paste")
			(net "M_G_VREF")
		)
		(pad "147" smd rect
			(at -4.59994 1.700022 270)
			(size 1.8034 0.508)
			(layers "B.Cu" "B.Mask" "B.Paste")
			(net "GND")
		)
		(pad "148" smd rect
			(at -4.59994 2.549906 270)
			(size 1.8034 0.508)
			(layers "B.Cu" "B.Mask" "B.Paste")
			(net "M_G_DQ<5>")
		)
	)
)
